FILE_TYPE = CONNECTIVITY;
{Allegro Design Entry HDL 17.4-2019 S026 (4007227) 1/17/2022}
"PAGE_NUMBER" = 92;
0"NC";
1"GND\g";
2"GND\g";
3"P3V3\g";
4"M_H_CPU0_SB_CB<7:0>";
5"M_H_CPU0_SA_DQ<31:0>";
6"M_H_CPU0_SA_CA<6:0>";
7"M_H_CPU0_SB_DQS_DP<9:0>";
8"M_H_CPU0_SB_DQS_DN<9:0>";
9"M_H_CPU0_SA_DQS_DP<9:0>";
10"M_H_CPU0_SA_DQS_DN<9:0>";
11"M_H_CPU0_SB_DQ<31:0>";
12"M_H_CPU0_SA_CB<7:0>";
13"M_H_CPU0_SB_CA<6:0>";
14"M_H_CPU0_SB_CB<2>";
15"M_H_CPU0_ALERT_N";
16"I3C_SPD_DDRGL_CPU0_SDA";
17"I3C_SPD_DDRH_CPU0_SCL";
18"I3C_SPD_DDRH_CPU0_SDA";
19"I3C_SPD_DDRGL_CPU0_SCL";
20"PD_CHH_CPU0_DIMM_SAA";
21"P3V3_AUX\g";
22"PWRGD_CHH_CPU0_DIMM";
23"M_H_CPU0_SB_RSP<0>";
24"M_H_CPU0_SA_RSP<0>";
25"M_H_CPU0_SA_DQ<17>";
26"PD_CHH_CPU0_DIMM_SAA";
27"M_H_CPU0_SA_CB<7>";
28"M_H_CPU0_SA_CB<4>";
29"M_H_CPU0_SA_CB<1>";
30"M_H_CPU0_SB_CB<7>";
31"M_H_CPU0_SA_CA<0>";
32"M_H_CPU0_SB_CA<0>";
33"M_H_CPU0_SA_CA<1>";
34"M_H_CPU0_SB_CA<1>";
35"M_H_CPU0_SA_CA<2>";
36"M_H_CPU0_SB_CA<2>";
37"M_H_CPU0_SA_CA<3>";
38"M_H_CPU0_SB_CA<3>";
39"M_H_CPU0_SB_CA<4>";
40"M_H_CPU0_SB_CA<5>";
41"M_H_CPU0_SB_CA<6>";
42"M_H_CPU0_SA_CB<6>";
43"M_H_CPU0_SA_CB<5>";
44"M_H_CPU0_SA_CB<3>";
45"M_H_CPU0_SA_CB<2>";
46"M_H_CPU0_SA_CB<0>";
47"M_H_CPU0_SB_CB<6>";
48"M_H_CPU0_SB_CB<4>";
49"M_H_CPU0_SB_CB<3>";
50"M_H_CPU0_SB_CB<1>";
51"M_H_CPU0_SB_CB<0>";
52"M_H_CPU0_CLK_DN<0>";
53"M_H_CPU0_CLK_DP<0>";
54"M_H_CPU0_SA_CS_N<0>";
55"M_H_CPU0_SB_CS_N<0>";
56"M_H_CPU0_SA_CS_N<1>";
57"M_H_CPU0_SB_CS_N<1>";
58"M_H_CPU0_SA_DQ<30>";
59"M_H_CPU0_SA_DQ<29>";
60"M_H_CPU0_SA_DQ<28>";
61"M_H_CPU0_SA_DQ<27>";
62"M_H_CPU0_SA_DQ<26>";
63"M_H_CPU0_SA_DQ<25>";
64"M_H_CPU0_SA_DQ<24>";
65"M_H_CPU0_SA_DQ<23>";
66"M_H_CPU0_SA_DQ<22>";
67"M_H_CPU0_SA_DQ<21>";
68"M_H_CPU0_SA_DQ<20>";
69"M_H_CPU0_SA_DQ<19>";
70"M_H_CPU0_SA_DQ<18>";
71"M_H_CPU0_SA_DQ<16>";
72"M_H_CPU0_SA_DQ<15>";
73"M_H_CPU0_SA_DQ<14>";
74"M_H_CPU0_SA_DQ<13>";
75"M_H_CPU0_SA_DQ<11>";
76"M_H_CPU0_SA_DQ<10>";
77"M_H_CPU0_SA_DQ<9>";
78"M_H_CPU0_SA_DQ<8>";
79"M_H_CPU0_SA_DQ<7>";
80"M_H_CPU0_SA_DQ<6>";
81"M_H_CPU0_SA_DQ<5>";
82"M_H_CPU0_SA_DQ<4>";
83"M_H_CPU0_SA_DQ<3>";
84"M_H_CPU0_SA_DQ<2>";
85"M_H_CPU0_SA_DQ<1>";
86"M_H_CPU0_SA_DQ<0>";
87"M_H_CPU0_SB_DQ<31>";
88"M_H_CPU0_SB_DQ<30>";
89"M_H_CPU0_SB_DQ<29>";
90"M_H_CPU0_SB_DQ<28>";
91"M_H_CPU0_SB_DQ<27>";
92"M_H_CPU0_SB_DQ<26>";
93"M_H_CPU0_SB_DQ<25>";
94"M_H_CPU0_SB_DQ<24>";
95"M_H_CPU0_SB_DQ<23>";
96"M_H_CPU0_SB_DQ<22>";
97"M_H_CPU0_SB_DQ<21>";
98"M_H_CPU0_SB_DQ<20>";
99"M_H_CPU0_SB_DQ<19>";
100"M_H_CPU0_SB_DQ<18>";
101"M_H_CPU0_SB_DQ<17>";
102"M_H_CPU0_SB_DQ<16>";
103"M_H_CPU0_SB_DQ<15>";
104"M_H_CPU0_SB_DQ<14>";
105"M_H_CPU0_SB_DQ<13>";
106"M_H_CPU0_SB_DQ<12>";
107"M_H_CPU0_SB_DQ<11>";
108"M_H_CPU0_SB_DQ<10>";
109"M_H_CPU0_SB_DQ<9>";
110"M_H_CPU0_SB_DQ<8>";
111"M_H_CPU0_SB_DQ<7>";
112"M_H_CPU0_SB_DQ<6>";
113"M_H_CPU0_SB_DQ<5>";
114"M_H_CPU0_SB_DQ<4>";
115"M_H_CPU0_SB_DQ<3>";
116"M_H_CPU0_SB_DQ<2>";
117"M_H_CPU0_SB_DQ<1>";
118"M_H_CPU0_SB_DQ<0>";
119"M_H_CPU0_SA_PAR";
120"M_H_CPU0_SB_PAR";
121"M_H_CPU0_SA_DQ<31>";
122"M_H_CPU0_SA_DQS_DN<7>";
123"M_H_CPU0_SA_DQS_DP<6>";
124"M_H_CPU0_SB_DQS_DP<8>";
125"M_H_CPU0_SB_DQS_DN<8>";
126"M_H_CPU0_SB_DQS_DP<7>";
127"M_H_CPU0_SA_DQS_DN<0>";
128"M_H_CPU0_SA_DQS_DP<0>";
129"M_H_CPU0_SB_DQS_DN<0>";
130"M_H_CPU0_SB_DQS_DP<0>";
131"M_H_CPU0_SA_DQS_DN<1>";
132"M_H_CPU0_SA_DQS_DP<1>";
133"M_H_CPU0_SB_DQS_DN<1>";
134"M_H_CPU0_SB_DQS_DP<1>";
135"M_H_CPU0_SA_DQS_DN<2>";
136"M_H_CPU0_SA_DQS_DP<2>";
137"M_H_CPU0_SB_DQS_DN<2>";
138"M_H_CPU0_SB_DQS_DP<2>";
139"M_H_CPU0_SA_DQS_DN<3>";
140"M_H_CPU0_SA_DQS_DP<3>";
141"M_H_CPU0_SB_DQS_DN<3>";
142"M_H_CPU0_SB_DQS_DP<3>";
143"M_H_CPU0_SA_DQS_DN<4>";
144"M_H_CPU0_SA_DQS_DP<4>";
145"M_H_CPU0_SB_DQS_DN<4>";
146"M_H_CPU0_SB_DQS_DP<4>";
147"M_H_CPU0_SA_DQS_DN<5>";
148"M_H_CPU0_SA_DQS_DP<5>";
149"M_H_CPU0_SB_DQS_DN<5>";
150"M_H_CPU0_SB_DQS_DP<5>";
151"M_H_CPU0_SA_DQS_DN<6>";
152"M_H_CPU0_SB_DQS_DN<6>";
153"M_H_CPU0_SB_DQS_DP<6>";
154"M_H_CPU0_SA_DQS_DP<7>";
155"M_H_CPU0_SB_DQS_DN<7>";
156"M_H_CPU0_SA_DQS_DN<8>";
157"M_H_CPU0_SA_DQS_DP<8>";
158"M_H_CPU0_SA_DQS_DN<9>";
159"M_H_CPU0_SA_DQS_DP<9>";
160"M_H_CPU0_SB_DQS_DN<9>";
161"M_H_CPU0_SB_DQS_DP<9>";
162"M_H_CPU0_SA_CA<4>";
163"M_H_CPU0_SA_CA<5>";
164"M_H_CPU0_SA_CA<6>";
165"M_H_CPU0_SA_DQ<12>";
166"M_H_CPU0_SB_CB<5>";
167"M_H_CPU0_RESET_N";
168"P12V_MEM_CPU0\g";
169"GND\g";
170"GND\g";
171"GND\g";
172"PWRGD_CHGL_CPU0";
%"TAP"
"1","(-6025,4150)","0","mstr_standard","I100";
;
CDS_LIB"mstr_standard"
BODY_TYPE"PLUMBING"
HDL_TAP"TRUE";
"B \NAC \NWC"5;
"S \NAC"
BN"7"79;
%"TAP"
"1","(-6025,4100)","0","mstr_standard","I101";
;
CDS_LIB"mstr_standard"
BODY_TYPE"PLUMBING"
HDL_TAP"TRUE";
"B \NAC \NWC"5;
"S \NAC"
BN"6"80;
%"TAP"
"1","(-6025,4200)","0","mstr_standard","I102";
;
CDS_LIB"mstr_standard"
BODY_TYPE"PLUMBING"
HDL_TAP"TRUE";
"B \NAC \NWC"5;
"S \NAC"
BN"8"78;
%"TAP"
"1","(-6025,4250)","0","mstr_standard","I103";
;
CDS_LIB"mstr_standard"
BODY_TYPE"PLUMBING"
HDL_TAP"TRUE";
"B \NAC \NWC"5;
"S \NAC"
BN"9"77;
%"TAP"
"1","(-6025,4350)","0","mstr_standard","I104";
;
CDS_LIB"mstr_standard"
BODY_TYPE"PLUMBING"
HDL_TAP"TRUE";
"B \NAC \NWC"5;
"S \NAC"
BN"11"75;
%"TAP"
"1","(-6025,4400)","0","mstr_standard","I105";
;
CDS_LIB"mstr_standard"
BODY_TYPE"PLUMBING"
HDL_TAP"TRUE";
"B \NAC \NWC"5;
"S \NAC"
BN"12"165;
%"TAP"
"1","(-6025,4450)","0","mstr_standard","I106";
;
CDS_LIB"mstr_standard"
BODY_TYPE"PLUMBING"
HDL_TAP"TRUE";
"B \NAC \NWC"5;
"S \NAC"
BN"13"74;
%"TAP"
"1","(-6025,4500)","0","mstr_standard","I107";
;
CDS_LIB"mstr_standard"
BODY_TYPE"PLUMBING"
HDL_TAP"TRUE";
"B \NAC \NWC"5;
"S \NAC"
BN"14"73;
%"TAP"
"1","(-6025,4300)","0","mstr_standard","I108";
;
CDS_LIB"mstr_standard"
BODY_TYPE"PLUMBING"
HDL_TAP"TRUE";
"B \NAC \NWC"5;
"S \NAC"
BN"10"76;
%"TAP"
"1","(-6025,4750)","0","mstr_standard","I109";
;
CDS_LIB"mstr_standard"
BODY_TYPE"PLUMBING"
HDL_TAP"TRUE";
"B \NAC \NWC"5;
"S \NAC"
BN"19"69;
%"TAP"
"1","(-6025,4600)","0","mstr_standard","I110";
;
CDS_LIB"mstr_standard"
BODY_TYPE"PLUMBING"
HDL_TAP"TRUE";
"B \NAC \NWC"5;
"S \NAC"
BN"16"71;
%"TAP"
"1","(-6025,4700)","0","mstr_standard","I111";
;
CDS_LIB"mstr_standard"
BODY_TYPE"PLUMBING"
HDL_TAP"TRUE";
"B \NAC \NWC"5;
"S \NAC"
BN"18"70;
%"TAP"
"1","(-6025,4650)","0","mstr_standard","I112";
;
CDS_LIB"mstr_standard"
BODY_TYPE"PLUMBING"
HDL_TAP"TRUE";
"B \NAC \NWC"5;
"S \NAC"
BN"17"25;
%"TAP"
"1","(-6025,4550)","0","mstr_standard","I113";
;
CDS_LIB"mstr_standard"
BODY_TYPE"PLUMBING"
HDL_TAP"TRUE";
"B \NAC \NWC"5;
"S \NAC"
BN"15"72;
%"TAP"
"1","(-6025,4800)","0","mstr_standard","I114";
;
CDS_LIB"mstr_standard"
BODY_TYPE"PLUMBING"
HDL_TAP"TRUE";
"B \NAC \NWC"5;
"S \NAC"
BN"20"68;
%"TAP"
"1","(-6025,4850)","0","mstr_standard","I115";
;
CDS_LIB"mstr_standard"
BODY_TYPE"PLUMBING"
HDL_TAP"TRUE";
"B \NAC \NWC"5;
"S \NAC"
BN"21"67;
%"TAP"
"1","(-6025,4900)","0","mstr_standard","I116";
;
CDS_LIB"mstr_standard"
BODY_TYPE"PLUMBING"
HDL_TAP"TRUE";
"B \NAC \NWC"5;
"S \NAC"
BN"22"66;
%"TAP"
"1","(-6025,5050)","0","mstr_standard","I117";
;
CDS_LIB"mstr_standard"
BODY_TYPE"PLUMBING"
HDL_TAP"TRUE";
"B \NAC \NWC"5;
"S \NAC"
BN"25"63;
%"TAP"
"1","(-6025,4950)","0","mstr_standard","I118";
;
CDS_LIB"mstr_standard"
BODY_TYPE"PLUMBING"
HDL_TAP"TRUE";
"B \NAC \NWC"5;
"S \NAC"
BN"23"65;
%"TAP"
"1","(-6025,5000)","0","mstr_standard","I119";
;
CDS_LIB"mstr_standard"
BODY_TYPE"PLUMBING"
HDL_TAP"TRUE";
"B \NAC \NWC"5;
"S \NAC"
BN"24"64;
%"TAP"
"1","(-6025,5250)","0","mstr_standard","I120";
;
CDS_LIB"mstr_standard"
BODY_TYPE"PLUMBING"
HDL_TAP"TRUE";
"B \NAC \NWC"5;
"S \NAC"
BN"29"59;
%"TAP"
"1","(-6025,5300)","0","mstr_standard","I121";
;
CDS_LIB"mstr_standard"
BODY_TYPE"PLUMBING"
HDL_TAP"TRUE";
"B \NAC \NWC"5;
"S \NAC"
BN"30"58;
%"TAP"
"1","(-6025,5200)","0","mstr_standard","I122";
;
CDS_LIB"mstr_standard"
BODY_TYPE"PLUMBING"
HDL_TAP"TRUE";
"B \NAC \NWC"5;
"S \NAC"
BN"28"60;
%"TAP"
"1","(-6025,5150)","0","mstr_standard","I123";
;
CDS_LIB"mstr_standard"
BODY_TYPE"PLUMBING"
HDL_TAP"TRUE";
"B \NAC \NWC"5;
"S \NAC"
BN"27"61;
%"TAP"
"1","(-6025,5100)","0","mstr_standard","I124";
;
CDS_LIB"mstr_standard"
BODY_TYPE"PLUMBING"
HDL_TAP"TRUE";
"B \NAC \NWC"5;
"S \NAC"
BN"26"62;
%"TAP"
"1","(-6025,5350)","0","mstr_standard","I125";
;
CDS_LIB"mstr_standard"
BODY_TYPE"PLUMBING"
HDL_TAP"TRUE";
"B \NAC \NWC"5;
"S \NAC"
BN"31"121;
%"GND"
"1","(-6425,875)","0","mstr_symbols","I128";
;
VOLTAGE"0.0"
BOM_COST"MEM"
CDS_LIB"mstr_symbols"
SIZE"1B"
BODY_TYPE"PLUMBING"
HDL_POWER"GND";
"A\NAC"1;
%"Q_RES"
"2","(-6425,1175)","0","pure_quanta","I129";
;
LOCATION"R765"
$SEC"1"
CDS_SEC"1"
PACK_TYPE"0402LF"
VALUE"15.4K"
TOLERANCE"1%"
MATERIAL"CHIP"
WATTAGE"1/16W"
CDS_LIB"pure_quanta"
PART_NUMBER"CS31542FB02";
"A"
$PN"1"26;
"B"
$PN"2"1;
%"GND"
"1","(-2200,1875)","0","mstr_symbols","I140";
;
VOLTAGE"0.0"
CDS_LIB"mstr_symbols"
SIZE"1B"
BODY_TYPE"PLUMBING"
HDL_POWER"GND";
"A\NAC"171;
%"GND"
"1","(-400,1650)","0","mstr_symbols","I141";
;
VOLTAGE"0.0"
CDS_LIB"mstr_symbols"
SIZE"1B"
BODY_TYPE"PLUMBING"
HDL_POWER"GND";
"A\NAC"170;
%"SCONN288_DDR506112002KQ"
"3","(-1300,3650)","0","pure_quanta","I177";
;
LOCATION"J69"
$SEC"3"
CDS_SEC"3"
VALUE"SCONN288_DDR506112002KQ"
MATERIAL"IO"
PART_TYPE"SMLF"
CDS_LIB"pure_quanta"
NEEDS_NO_SIZE"TRUE"
CDS_LMAN_SYM_OUTLINE"-450,1800,450,-1750"
PART_NUMBER"DFHST8FS479";
"G3"
$PN"G3"170;
"G2"
$PN"G2"170;
"G1"
$PN"G1"170;
"VSS62"
$PN"141"170;
"VSS61"
$PN"139"170;
"VSS60"
$PN"136"170;
"VSS58"
$PN"132"170;
"VSS104"
$PN"240"171;
"VSS102"
$PN"235"171;
"VSS100"
$PN"230"171;
"VIN_BULK2"
$PN"146"168;
"VIN_BULK1"
$PN"145"168;
"VIN_BULK0"
$PN"1"168;
"VSS126"
$PN"288"171;
"VSS125"
$PN"286"171;
"VSS124"
$PN"284"171;
"VSS123"
$PN"281"171;
"VSS122"
$PN"279"171;
"VSS121"
$PN"277"171;
"VSS120"
$PN"275"171;
"VSS119"
$PN"273"171;
"VSS118"
$PN"270"171;
"VSS117"
$PN"268"171;
"VSS116"
$PN"266"171;
"VSS115"
$PN"264"171;
"VSS114"
$PN"262"171;
"VSS113"
$PN"259"171;
"VSS112"
$PN"257"171;
"VSS111"
$PN"255"171;
"VSS110"
$PN"253"171;
"VSS109"
$PN"251"171;
"VSS108"
$PN"248"171;
"VSS107"
$PN"246"171;
"VSS106"
$PN"244"171;
"VSS105"
$PN"242"171;
"VSS103"
$PN"237"171;
"VSS101"
$PN"233"171;
"VSS99"
$PN"228"171;
"VSS98"
$PN"226"171;
"VSS97"
$PN"224"171;
"VSS96"
$PN"222"171;
"VSS95"
$PN"219"171;
"VSS94"
$PN"216"171;
"VSS93"
$PN"214"171;
"VSS92"
$PN"212"171;
"VSS91"
$PN"210"171;
"VSS90"
$PN"208"171;
"VSS89"
$PN"206"171;
"VSS88"
$PN"204"171;
"VSS87"
$PN"202"171;
"VSS86"
$PN"199"171;
"VSS85"
$PN"197"171;
"VSS84"
$PN"195"171;
"VSS83"
$PN"193"171;
"VSS82"
$PN"191"171;
"VSS81"
$PN"188"171;
"VSS80"
$PN"186"171;
"VSS79"
$PN"184"171;
"VSS78"
$PN"182"171;
"VSS77"
$PN"180"171;
"VSS76"
$PN"177"171;
"VSS75"
$PN"175"171;
"VSS74"
$PN"173"171;
"VSS73"
$PN"171"171;
"VSS72"
$PN"169"171;
"VSS71"
$PN"166"171;
"VSS70"
$PN"164"171;
"VSS69"
$PN"162"171;
"VSS68"
$PN"160"171;
"VSS67"
$PN"158"171;
"VSS66"
$PN"155"171;
"VSS65"
$PN"153"171;
"VSS64"
$PN"151"171;
"VSS63"
$PN"143"170;
"VSS59"
$PN"134"170;
"VSS57"
$PN"130"170;
"VSS56"
$PN"128"170;
"VSS55"
$PN"125"170;
"VSS54"
$PN"123"170;
"VSS53"
$PN"121"170;
"VSS52"
$PN"119"170;
"VSS51"
$PN"117"170;
"VSS50"
$PN"114"170;
"VSS49"
$PN"112"170;
"VSS48"
$PN"110"170;
"VSS47"
$PN"108"170;
"VSS46"
$PN"106"170;
"VSS45"
$PN"103"170;
"VSS44"
$PN"101"170;
"VSS43"
$PN"99"170;
"VSS42"
$PN"97"170;
"VSS41"
$PN"95"170;
"VSS40"
$PN"92"170;
"VSS39"
$PN"90"170;
"VSS38"
$PN"88"170;
"VSS37"
$PN"85"170;
"VSS36"
$PN"83"170;
"VSS35"
$PN"81"170;
"VSS34"
$PN"79"170;
"VSS33"
$PN"77"170;
"VSS32"
$PN"75"170;
"VSS31"
$PN"73"170;
"VSS30"
$PN"71"170;
"VSS29"
$PN"69"170;
"VSS28"
$PN"67"170;
"VSS27"
$PN"65"170;
"VSS26"
$PN"63"170;
"VSS25"
$PN"61"170;
"VSS24"
$PN"59"170;
"VSS23"
$PN"57"170;
"VSS22"
$PN"54"170;
"VSS21"
$PN"52"170;
"VSS20"
$PN"50"170;
"VSS19"
$PN"48"170;
"VSS18"
$PN"46"170;
"VSS17"
$PN"43"170;
"VSS16"
$PN"41"170;
"VSS15"
$PN"39"170;
"VSS14"
$PN"37"170;
"VSS13"
$PN"35"170;
"VSS12"
$PN"32"170;
"VSS11"
$PN"30"170;
"VSS10"
$PN"28"170;
"VSS9"
$PN"26"170;
"VSS8"
$PN"24"170;
"VSS7"
$PN"21"170;
"VSS6"
$PN"19"170;
"VSS5"
$PN"17"170;
"VSS4"
$PN"15"170;
"VSS3"
$PN"13"170;
"VSS2"
$PN"10"170;
"VSS1"
$PN"8"170;
"VSS0"
$PN"6"170;
%"Q_CAP"
"1","(-8650,3175)","2","pure_quanta","I186";
;
LOCATION"C116"
$SEC"1"
CDS_SEC"1"
PACK_TYPE"0402"
MATERIAL"X7R"
TOLERANCE"10%"
VALUE"0.1UF"
VOLTAGE"25V"
BOM_COST"MEM"
CDS_LIB"pure_quanta"
ROOM""
PART_NUMBER"CH4104K1B00";
"B"
$PN"2"2;
"A"
$PN"1"21;
%"GND"
"1","(-8650,2950)","0","mstr_symbols","I187";
;
ROOM"MEM_EFGH_DECOUPLING_CAPS"
VOLTAGE"0"
CDS_LIB"mstr_symbols"
SIZE"1B"
BOM_COST"MEM"
BODY_TYPE"PLUMBING"
HDL_POWER"GND";
"A\NAC"2;
%"Q_RES"
"1","(-8525,2100)","2","pure_quanta","I189";
;
LOCATION"R298"
$SEC"1"
CDS_SEC"1"
VALUE"1K"
PACK_TYPE"0402LF"
MATERIAL"CHIP"
WATTAGE"1/16W"
CDS_LIB"pure_quanta"
BOM_COST"MEM"
TOLERANCE"1%"
ROOM""
PART_NUMBER"CS21002FB06";
"B"
$PN"2"172;
"A"
$PN"1"22;
%"VCC_CORE"
"1","(-8400,2425)","0","mstr_symbols","I190";
;
HDL_POWER"P3V3"
ROOM"PVCCINFAON_CPU0_CTRL"
VOLTAGE"3.3"
CDS_LIB"mstr_symbols";
"A"3;
%"Q_RES"
"2","(-8400,2250)","0","pure_quanta","I191";
;
LOCATION"R97"
$SEC"1"
CDS_SEC"1"
VALUE"1K"
WATTAGE"1/16W"
MATERIAL"EMPTY"
PACK_TYPE"0402LF"
TOLERANCE"1%"
CDS_LIB"pure_quanta"
BOM_COST"MEM"
ROOM""
PART_NUMBER"CS21002FB06";
"A"
$PN"1"3;
"B"
$PN"2"22;
%"TAP"
"1","(-3300,4300)","0","mstr_standard","I197";
;
CDS_LIB"mstr_standard"
BODY_TYPE"PLUMBING"
HDL_TAP"TRUE";
"B \NAC \NWC"10;
"S \NAC"
BN"9"158;
%"TAP"
"1","(-3300,4200)","0","mstr_standard","I198";
;
CDS_LIB"mstr_standard"
BODY_TYPE"PLUMBING"
HDL_TAP"TRUE";
"B \NAC \NWC"10;
"S \NAC"
BN"8"156;
%"TAP"
"1","(-3500,4350)","0","mstr_standard","I199";
;
CDS_LIB"mstr_standard"
BODY_TYPE"PLUMBING"
HDL_TAP"TRUE";
"B \NAC \NWC"9;
"S \NAC"
BN"9"159;
%"TAP"
"1","(-3500,4250)","0","mstr_standard","I200";
;
CDS_LIB"mstr_standard"
BODY_TYPE"PLUMBING"
HDL_TAP"TRUE";
"B \NAC \NWC"9;
"S \NAC"
BN"8"157;
%"TAP"
"1","(-3300,4100)","0","mstr_standard","I201";
;
CDS_LIB"mstr_standard"
BODY_TYPE"PLUMBING"
HDL_TAP"TRUE";
"B \NAC \NWC"10;
"S \NAC"
BN"7"122;
%"TAP"
"1","(-3300,4000)","0","mstr_standard","I202";
;
CDS_LIB"mstr_standard"
BODY_TYPE"PLUMBING"
HDL_TAP"TRUE";
"B \NAC \NWC"10;
"S \NAC"
BN"6"151;
%"TAP"
"1","(-3300,3800)","0","mstr_standard","I203";
;
CDS_LIB"mstr_standard"
BODY_TYPE"PLUMBING"
HDL_TAP"TRUE";
"B \NAC \NWC"10;
"S \NAC"
BN"4"143;
%"TAP"
"1","(-3300,3900)","0","mstr_standard","I204";
;
CDS_LIB"mstr_standard"
BODY_TYPE"PLUMBING"
HDL_TAP"TRUE";
"B \NAC \NWC"10;
"S \NAC"
BN"5"147;
%"TAP"
"1","(-3300,3700)","0","mstr_standard","I205";
;
CDS_LIB"mstr_standard"
BODY_TYPE"PLUMBING"
HDL_TAP"TRUE";
"B \NAC \NWC"10;
"S \NAC"
BN"3"139;
%"TAP"
"1","(-3500,3950)","0","mstr_standard","I206";
;
CDS_LIB"mstr_standard"
BODY_TYPE"PLUMBING"
HDL_TAP"TRUE";
"B \NAC \NWC"9;
"S \NAC"
BN"5"148;
%"TAP"
"1","(-3500,4150)","0","mstr_standard","I207";
;
CDS_LIB"mstr_standard"
BODY_TYPE"PLUMBING"
HDL_TAP"TRUE";
"B \NAC \NWC"9;
"S \NAC"
BN"7"154;
%"TAP"
"1","(-3500,4050)","0","mstr_standard","I208";
;
CDS_LIB"mstr_standard"
BODY_TYPE"PLUMBING"
HDL_TAP"TRUE";
"B \NAC \NWC"9;
"S \NAC"
BN"6"123;
%"TAP"
"1","(-3500,3850)","0","mstr_standard","I209";
;
CDS_LIB"mstr_standard"
BODY_TYPE"PLUMBING"
HDL_TAP"TRUE";
"B \NAC \NWC"9;
"S \NAC"
BN"4"144;
%"TAP"
"1","(-3500,3750)","0","mstr_standard","I210";
;
CDS_LIB"mstr_standard"
BODY_TYPE"PLUMBING"
HDL_TAP"TRUE";
"B \NAC \NWC"9;
"S \NAC"
BN"3"140;
%"TAP"
"1","(-3300,3600)","0","mstr_standard","I211";
;
CDS_LIB"mstr_standard"
BODY_TYPE"PLUMBING"
HDL_TAP"TRUE";
"B \NAC \NWC"10;
"S \NAC"
BN"2"135;
%"TAP"
"1","(-3300,3500)","0","mstr_standard","I212";
;
CDS_LIB"mstr_standard"
BODY_TYPE"PLUMBING"
HDL_TAP"TRUE";
"B \NAC \NWC"10;
"S \NAC"
BN"1"131;
%"TAP"
"1","(-3300,3400)","0","mstr_standard","I213";
;
CDS_LIB"mstr_standard"
BODY_TYPE"PLUMBING"
HDL_TAP"TRUE";
"B \NAC \NWC"10;
"S \NAC"
BN"0"127;
%"TAP"
"1","(-3300,3150)","0","mstr_standard","I214";
;
CDS_LIB"mstr_standard"
BODY_TYPE"PLUMBING"
HDL_TAP"TRUE";
"B \NAC \NWC"8;
"S \NAC"
BN"8"125;
%"TAP"
"1","(-3300,3250)","0","mstr_standard","I215";
;
CDS_LIB"mstr_standard"
BODY_TYPE"PLUMBING"
HDL_TAP"TRUE";
"B \NAC \NWC"8;
"S \NAC"
BN"9"160;
%"TAP"
"1","(-3500,3450)","0","mstr_standard","I216";
;
CDS_LIB"mstr_standard"
BODY_TYPE"PLUMBING"
HDL_TAP"TRUE";
"B \NAC \NWC"9;
"S \NAC"
BN"0"128;
%"TAP"
"1","(-3500,3650)","0","mstr_standard","I217";
;
CDS_LIB"mstr_standard"
BODY_TYPE"PLUMBING"
HDL_TAP"TRUE";
"B \NAC \NWC"9;
"S \NAC"
BN"2"136;
%"TAP"
"1","(-3500,3550)","0","mstr_standard","I218";
;
CDS_LIB"mstr_standard"
BODY_TYPE"PLUMBING"
HDL_TAP"TRUE";
"B \NAC \NWC"9;
"S \NAC"
BN"1"132;
%"TAP"
"1","(-3500,3200)","0","mstr_standard","I219";
;
CDS_LIB"mstr_standard"
BODY_TYPE"PLUMBING"
HDL_TAP"TRUE";
"B \NAC \NWC"7;
"S \NAC"
BN"8"124;
%"SCONN288_DDR506112002KQ"
"1","(-6875,3600)","0","pure_quanta","I22";
;
LOCATION"J69"
$SEC"1"
CDS_SEC"1"
VALUE"SCONN288_DDR506112002KQ"
MATERIAL"IO"
PART_TYPE"SMLF"
CDS_LIB"pure_quanta"
NEEDS_NO_SIZE"TRUE"
CDS_LMAN_SYM_OUTLINE"-450,1900,450,-1850"
PART_NUMBER"DFHST8FS479";
"PWR_GOOD||FAIL_N"
$PN"147"22;
"DQ31_A"
$PN"194"121;
"CB7_A"
$PN"205"27;
"CB4_A"
$PN"58"28;
"CB1_A"
$PN"53"29;
"CB7_B"
$PN"236"30;
"ALERT_N \B"
$PN"62"15;
"CA0_A"
$PN"66"31;
"CA0_B"
$PN"76"32;
"CA1_A"
$PN"211"33;
"CA1_B"
$PN"221"34;
"CA2_A"
$PN"68"35;
"CA2_B"
$PN"78"36;
"CA3_A"
$PN"213"37;
"CA3_B"
$PN"223"38;
"CA4_A"
$PN"70"162;
"CA4_B"
$PN"80"39;
"CA5_A"
$PN"215"163;
"CA5_B"
$PN"225"40;
"CA6_A"
$PN"72"164;
"CA6_B"
$PN"82"41;
"CB6_A"
$PN"203"42;
"CB5_A"
$PN"60"43;
"CB3_A"
$PN"198"44;
"CB2_A"
$PN"196"45;
"CB0_A"
$PN"51"46;
"CB6_B"
$PN"234"47;
"CB5_B"
$PN"91"166;
"CB4_B"
$PN"89"48;
"CB3_B"
$PN"243"49;
"CB2_B"
$PN"241"14;
"CB1_B"
$PN"98"50;
"CB0_B"
$PN"96"51;
"CK_C \B"
$PN"218"52;
"CK_T"
$PN"217"53;
"CS0_A_N"
$PN"64"54;
"CS0_B_N"
$PN"84"55;
"CS1_A_N"
$PN"209"56;
"CS1_B_N"
$PN"229"57;
"DQ30_A"
$PN"192"58;
"DQ29_A"
$PN"49"59;
"DQ28_A"
$PN"47"60;
"DQ27_A"
$PN"187"61;
"DQ26_A"
$PN"185"62;
"DQ25_A"
$PN"42"63;
"DQ24_A"
$PN"40"64;
"DQ23_A"
$PN"183"65;
"DQ22_A"
$PN"181"66;
"DQ21_A"
$PN"38"67;
"DQ20_A"
$PN"36"68;
"DQ19_A"
$PN"176"69;
"DQ18_A"
$PN"174"70;
"DQ17_A"
$PN"31"25;
"DQ16_A"
$PN"29"71;
"DQ15_A"
$PN"172"72;
"DQ14_A"
$PN"170"73;
"DQ13_A"
$PN"27"74;
"DQ12_A"
$PN"25"165;
"DQ11_A"
$PN"165"75;
"DQ10_A"
$PN"163"76;
"DQ9_A"
$PN"20"77;
"DQ8_A"
$PN"18"78;
"DQ7_A"
$PN"161"79;
"DQ6_A"
$PN"159"80;
"DQ5_A"
$PN"16"81;
"DQ4_A"
$PN"14"82;
"DQ3_A"
$PN"154"83;
"DQ2_A"
$PN"152"84;
"DQ1_A"
$PN"9"85;
"DQ0_A"
$PN"7"86;
"DQ31_B"
$PN"287"87;
"DQ30_B"
$PN"285"88;
"DQ29_B"
$PN"142"89;
"DQ28_B"
$PN"140"90;
"DQ27_B"
$PN"280"91;
"DQ26_B"
$PN"278"92;
"DQ25_B"
$PN"135"93;
"DQ24_B"
$PN"133"94;
"DQ23_B"
$PN"276"95;
"DQ22_B"
$PN"274"96;
"DQ21_B"
$PN"131"97;
"DQ20_B"
$PN"129"98;
"DQ19_B"
$PN"269"99;
"DQ18_B"
$PN"267"100;
"DQ17_B"
$PN"124"101;
"DQ16_B"
$PN"122"102;
"DQ15_B"
$PN"265"103;
"DQ14_B"
$PN"263"104;
"DQ13_B"
$PN"120"105;
"DQ12_B"
$PN"118"106;
"DQ11_B"
$PN"258"107;
"DQ10_B"
$PN"256"108;
"DQ9_B"
$PN"113"109;
"DQ8_B"
$PN"111"110;
"DQ7_B"
$PN"254"111;
"DQ6_B"
$PN"252"112;
"DQ5_B"
$PN"109"113;
"DQ4_B"
$PN"107"114;
"DQ3_B"
$PN"247"115;
"DQ2_B"
$PN"245"116;
"DQ1_B"
$PN"102"117;
"DQ0_B"
$PN"100"118;
"HAS"
$PN"148"20;
"HSCL"
$PN"4"17;
"HSDA"
$PN"5"18;
"LBD||RSP_A_N"
$PN"86"24;
"LBS||RSP_B_N"
$PN"87"23;
"PAR_A"
$PN"74"119;
"PAR_B"
$PN"227"120;
"RESET_N \B"
$PN"207"167;
"RFU6"
$PN"232"0;
"RFU5"
$PN"231"0;
"RFU4"
$PN"220"0;
"RFU3"
$PN"150"0;
"RFU2"
$PN"149"0;
"RFU1"
$PN"144"0;
"RFU0"
$PN"2"0;
"VIN_MGMT"
$PN"3"21;
%"TAP"
"1","(-3500,3300)","0","mstr_standard","I220";
;
CDS_LIB"mstr_standard"
BODY_TYPE"PLUMBING"
HDL_TAP"TRUE";
"B \NAC \NWC"7;
"S \NAC"
BN"9"161;
%"TAP"
"1","(-3300,3050)","0","mstr_standard","I221";
;
CDS_LIB"mstr_standard"
BODY_TYPE"PLUMBING"
HDL_TAP"TRUE";
"B \NAC \NWC"8;
"S \NAC"
BN"7"155;
%"TAP"
"1","(-3300,2950)","0","mstr_standard","I222";
;
CDS_LIB"mstr_standard"
BODY_TYPE"PLUMBING"
HDL_TAP"TRUE";
"B \NAC \NWC"8;
"S \NAC"
BN"6"152;
%"TAP"
"1","(-3300,2850)","0","mstr_standard","I223";
;
CDS_LIB"mstr_standard"
BODY_TYPE"PLUMBING"
HDL_TAP"TRUE";
"B \NAC \NWC"8;
"S \NAC"
BN"5"149;
%"TAP"
"1","(-3300,2650)","0","mstr_standard","I224";
;
CDS_LIB"mstr_standard"
BODY_TYPE"PLUMBING"
HDL_TAP"TRUE";
"B \NAC \NWC"8;
"S \NAC"
BN"3"141;
%"TAP"
"1","(-3300,2750)","0","mstr_standard","I225";
;
CDS_LIB"mstr_standard"
BODY_TYPE"PLUMBING"
HDL_TAP"TRUE";
"B \NAC \NWC"8;
"S \NAC"
BN"4"145;
%"TAP"
"1","(-3500,2900)","0","mstr_standard","I226";
;
CDS_LIB"mstr_standard"
BODY_TYPE"PLUMBING"
HDL_TAP"TRUE";
"B \NAC \NWC"7;
"S \NAC"
BN"5"150;
%"TAP"
"1","(-3500,3100)","0","mstr_standard","I227";
;
CDS_LIB"mstr_standard"
BODY_TYPE"PLUMBING"
HDL_TAP"TRUE";
"B \NAC \NWC"7;
"S \NAC"
BN"7"126;
%"TAP"
"1","(-3500,3000)","0","mstr_standard","I228";
;
CDS_LIB"mstr_standard"
BODY_TYPE"PLUMBING"
HDL_TAP"TRUE";
"B \NAC \NWC"7;
"S \NAC"
BN"6"153;
%"TAP"
"1","(-3500,2800)","0","mstr_standard","I229";
;
CDS_LIB"mstr_standard"
BODY_TYPE"PLUMBING"
HDL_TAP"TRUE";
"B \NAC \NWC"7;
"S \NAC"
BN"4"146;
%"TAP"
"1","(-7725,3150)","2","mstr_standard","I23";
;
CDS_LIB"mstr_standard"
BODY_TYPE"PLUMBING"
HDL_TAP"TRUE";
"B \NAC \NWC"4;
"S \NAC"
BN"0"51;
%"TAP"
"1","(-3500,2700)","0","mstr_standard","I230";
;
CDS_LIB"mstr_standard"
BODY_TYPE"PLUMBING"
HDL_TAP"TRUE";
"B \NAC \NWC"7;
"S \NAC"
BN"3"142;
%"TAP"
"1","(-3300,2550)","0","mstr_standard","I231";
;
CDS_LIB"mstr_standard"
BODY_TYPE"PLUMBING"
HDL_TAP"TRUE";
"B \NAC \NWC"8;
"S \NAC"
BN"2"137;
%"TAP"
"1","(-3300,2450)","0","mstr_standard","I232";
;
CDS_LIB"mstr_standard"
BODY_TYPE"PLUMBING"
HDL_TAP"TRUE";
"B \NAC \NWC"8;
"S \NAC"
BN"1"133;
%"TAP"
"1","(-3300,2350)","0","mstr_standard","I233";
;
CDS_LIB"mstr_standard"
BODY_TYPE"PLUMBING"
HDL_TAP"TRUE";
"B \NAC \NWC"8;
"S \NAC"
BN"0"129;
%"TAP"
"1","(-3500,2400)","0","mstr_standard","I234";
;
CDS_LIB"mstr_standard"
BODY_TYPE"PLUMBING"
HDL_TAP"TRUE";
"B \NAC \NWC"7;
"S \NAC"
BN"0"130;
%"TAP"
"1","(-3500,2500)","0","mstr_standard","I235";
;
CDS_LIB"mstr_standard"
BODY_TYPE"PLUMBING"
HDL_TAP"TRUE";
"B \NAC \NWC"7;
"S \NAC"
BN"1"134;
%"TAP"
"1","(-3500,2600)","0","mstr_standard","I236";
;
CDS_LIB"mstr_standard"
BODY_TYPE"PLUMBING"
HDL_TAP"TRUE";
"B \NAC \NWC"7;
"S \NAC"
BN"2"138;
%"SCONN288_DDR506112002KQ"
"2","(-4450,3350)","0","pure_quanta","I237";
;
LOCATION"J69"
$SEC"2"
CDS_SEC"2"
PART_TYPE"SMLF"
VALUE"SCONN288_DDR506112002KQ"
MATERIAL"IO"
CDS_LIB"pure_quanta"
NEEDS_NO_SIZE"TRUE"
CDS_LMAN_SYM_OUTLINE"-600,1150,600,-1150"
PART_NUMBER"DFHST8FS479";
"DQS7_A_C||TDQS7_A_C \B"
$PN"178"122;
"DQS6_A_T||TDQS6_A_T"
$PN"168"123;
"DQS8_B_T||TDQS8_B_T"
$PN"283"124;
"DQS8_B_C||TDQS8_B_C \B"
$PN"282"125;
"DQS7_B_T||TDQS7_B_T"
$PN"272"126;
"DQS0_A_C \B"
$PN"12"127;
"DQS0_A_T"
$PN"11"128;
"DQS0_B_C \B"
$PN"105"129;
"DQS0_B_T"
$PN"104"130;
"DQS1_A_C \B"
$PN"23"131;
"DQS1_A_T"
$PN"22"132;
"DQS1_B_C \B"
$PN"116"133;
"DQS1_B_T"
$PN"115"134;
"DQS2_A_C \B"
$PN"34"135;
"DQS2_A_T"
$PN"33"136;
"DQS2_B_C \B"
$PN"127"137;
"DQS2_B_T"
$PN"126"138;
"DQS3_A_C \B"
$PN"45"139;
"DQS3_A_T"
$PN"44"140;
"DQS3_B_C \B"
$PN"138"141;
"DQS3_B_T"
$PN"137"142;
"DQS4_A_C \B"
$PN"56"143;
"DQS4_A_T"
$PN"55"144;
"DQS4_B_C \B"
$PN"238"145;
"DQS4_B_T"
$PN"239"146;
"DQS5_A_C||TDQS5_A_C||DQS5_A_T||TDQS5_A_T \B"
$PN"156"147;
"DQS5_A_T||TDQS5_A_T"
$PN"157"148;
"DQS5_B_C||TDQS5_B_C \B"
$PN"249"149;
"DQS5_B_T||TDQS5_B_T"
$PN"250"150;
"DQS6_A_C||TDQS6_A_C||DQS6_A_T||TDQS6_A_T \B"
$PN"167"151;
"DQS6_B_C||TDQS6_B_C \B"
$PN"260"152;
"DQS6_B_T||TDQS6_B_T"
$PN"261"153;
"DQS7_A_T||TDQS7_A_T"
$PN"179"154;
"DQS7_B_C||TDQS7_B_C \B"
$PN"271"155;
"DQS8_A_C||TDQS8_A_C \B"
$PN"189"156;
"DQS8_A_T||TDQS8_A_T"
$PN"190"157;
"DQS9_A_C||TDQS9_A_C \B"
$PN"200"158;
"DQS9_A_T||TDQS9_A_T"
$PN"201"159;
"DQS9_B_C||TDQS9_B_C \B"
$PN"94"160;
"DQS9_B_T||TDQS9_B_T||DBI4_B_N"
$PN"93"161;
%"GND"
"1","(-2900,5650)","0","pure_quanta_power","I238";
;
ROOM"MEM_EFGH_DECOUPLING_CAPS"
SIZE"1B"
BOM_COST"MEM"
CDS_LIB"pure_quanta_power"
HDL_POWER"GND";
"A<SIZE-1..0>\NAC"169;
%"Q_CAP"
"1","(-2900,6000)","2","pure_quanta","I239";
;
LOCATION"C159"
$SEC"1"
CDS_SEC"1"
MATERIAL"X6S"
TOLERANCE"10%"
VALUE"10UF"
VOLTAGE"25V"
PACK_TYPE"C0805"
BOM_COST"MEM"
CDS_LIB"pure_quanta"
ROOM""
PART_NUMBER"CH6104KEA00";
"B"
$PN"2"169;
"A"
$PN"1"168;
%"TAP"
"1","(-7725,3200)","2","mstr_standard","I24";
;
CDS_LIB"mstr_standard"
BODY_TYPE"PLUMBING"
HDL_TAP"TRUE";
"B \NAC \NWC"4;
"S \NAC"
BN"1"50;
%"Q_CAP"
"1","(-2325,6000)","2","pure_quanta","I240";
;
LOCATION"C161"
$SEC"1"
CDS_SEC"1"
VALUE"10UF"
VOLTAGE"25V"
MATERIAL"X6S"
PACK_TYPE"C0805"
TOLERANCE"10%"
BOM_COST"MEM"
CDS_LIB"pure_quanta"
ROOM""
PART_NUMBER"CH6104KEA00";
"B"
$PN"2"169;
"A"
$PN"1"168;
%"UNIVERSAL_POWER"
"1","(-2900,6325)","0","pure_quanta_power","I241";
;
HDL_POWER"P12V_MEM_CPU0"
CDS_LIB"pure_quanta_power"
BOM_COST"VR_SYSTEM";
"A"168;
%"Q_RES"
"1","(-7750,2575)","0","pure_quanta","I243";
;
LOCATION"R1575"
$SEC"1"
CDS_SEC"1"
VALUE"49.9"
MATERIAL"CHIP"
PACK_TYPE"0402LF"
WATTAGE"1/16W"
TOLERANCE"1%"
CDS_LIB"pure_quanta"
PART_NUMBER"CS04992FB07";
"B"
$PN"2"17;
"A"
$PN"1"19;
%"Q_RES"
"1","(-8150,2800)","0","pure_quanta","I244";
;
LOCATION"R1681"
$SEC"1"
CDS_SEC"1"
MATERIAL"CHIP"
PACK_TYPE"0402LF"
VALUE"10"
CDS_LIB"pure_quanta"
WATTAGE"1/16W"
TOLERANCE"1%"
PART_NUMBER"CS01002FB07";
"B"
$PN"2"18;
"A"
$PN"1"16;
%"TAP"
"1","(-7725,3250)","2","mstr_standard","I25";
;
CDS_LIB"mstr_standard"
BODY_TYPE"PLUMBING"
HDL_TAP"TRUE";
"B \NAC \NWC"4;
"S \NAC"
BN"2"14;
%"TAP"
"1","(-7725,3300)","2","mstr_standard","I26";
;
CDS_LIB"mstr_standard"
BODY_TYPE"PLUMBING"
HDL_TAP"TRUE";
"B \NAC \NWC"4;
"S \NAC"
BN"3"49;
%"TAP"
"1","(-7725,3350)","2","mstr_standard","I27";
;
CDS_LIB"mstr_standard"
BODY_TYPE"PLUMBING"
HDL_TAP"TRUE";
"B \NAC \NWC"4;
"S \NAC"
BN"4"48;
%"TAP"
"1","(-7725,3450)","2","mstr_standard","I28";
;
CDS_LIB"mstr_standard"
BODY_TYPE"PLUMBING"
HDL_TAP"TRUE";
"B \NAC \NWC"4;
"S \NAC"
BN"6"47;
%"TAP"
"1","(-7725,3400)","2","mstr_standard","I29";
;
CDS_LIB"mstr_standard"
BODY_TYPE"PLUMBING"
HDL_TAP"TRUE";
"B \NAC \NWC"4;
"S \NAC"
BN"5"166;
%"TAP"
"1","(-7725,3500)","2","mstr_standard","I30";
;
CDS_LIB"mstr_standard"
BODY_TYPE"PLUMBING"
HDL_TAP"TRUE";
"B \NAC \NWC"4;
"S \NAC"
BN"7"30;
%"TAP"
"1","(-7725,3600)","2","mstr_standard","I31";
;
CDS_LIB"mstr_standard"
BODY_TYPE"PLUMBING"
HDL_TAP"TRUE";
"B \NAC \NWC"12;
"S \NAC"
BN"0"46;
%"TAP"
"1","(-7725,3650)","2","mstr_standard","I32";
;
CDS_LIB"mstr_standard"
BODY_TYPE"PLUMBING"
HDL_TAP"TRUE";
"B \NAC \NWC"12;
"S \NAC"
BN"1"29;
%"TAP"
"1","(-7725,3700)","2","mstr_standard","I33";
;
CDS_LIB"mstr_standard"
BODY_TYPE"PLUMBING"
HDL_TAP"TRUE";
"B \NAC \NWC"12;
"S \NAC"
BN"2"45;
%"TAP"
"1","(-7725,3750)","2","mstr_standard","I34";
;
CDS_LIB"mstr_standard"
BODY_TYPE"PLUMBING"
HDL_TAP"TRUE";
"B \NAC \NWC"12;
"S \NAC"
BN"3"44;
%"TAP"
"1","(-6025,2150)","0","mstr_standard","I35";
;
CDS_LIB"mstr_standard"
BODY_TYPE"PLUMBING"
HDL_TAP"TRUE";
"B \NAC \NWC"11;
"S \NAC"
BN"0"118;
%"TAP"
"1","(-6025,2200)","0","mstr_standard","I36";
;
CDS_LIB"mstr_standard"
BODY_TYPE"PLUMBING"
HDL_TAP"TRUE";
"B \NAC \NWC"11;
"S \NAC"
BN"1"117;
%"TAP"
"1","(-6025,2250)","0","mstr_standard","I37";
;
CDS_LIB"mstr_standard"
BODY_TYPE"PLUMBING"
HDL_TAP"TRUE";
"B \NAC \NWC"11;
"S \NAC"
BN"2"116;
%"TAP"
"1","(-6025,2300)","0","mstr_standard","I38";
;
CDS_LIB"mstr_standard"
BODY_TYPE"PLUMBING"
HDL_TAP"TRUE";
"B \NAC \NWC"11;
"S \NAC"
BN"3"115;
%"TAP"
"1","(-6025,2350)","0","mstr_standard","I39";
;
CDS_LIB"mstr_standard"
BODY_TYPE"PLUMBING"
HDL_TAP"TRUE";
"B \NAC \NWC"11;
"S \NAC"
BN"4"114;
%"TAP"
"1","(-6025,2400)","0","mstr_standard","I40";
;
CDS_LIB"mstr_standard"
BODY_TYPE"PLUMBING"
HDL_TAP"TRUE";
"B \NAC \NWC"11;
"S \NAC"
BN"5"113;
%"TAP"
"1","(-6025,2450)","0","mstr_standard","I41";
;
CDS_LIB"mstr_standard"
BODY_TYPE"PLUMBING"
HDL_TAP"TRUE";
"B \NAC \NWC"11;
"S \NAC"
BN"6"112;
%"TAP"
"1","(-6025,2500)","0","mstr_standard","I42";
;
CDS_LIB"mstr_standard"
BODY_TYPE"PLUMBING"
HDL_TAP"TRUE";
"B \NAC \NWC"11;
"S \NAC"
BN"7"111;
%"TAP"
"1","(-6025,2550)","0","mstr_standard","I43";
;
CDS_LIB"mstr_standard"
BODY_TYPE"PLUMBING"
HDL_TAP"TRUE";
"B \NAC \NWC"11;
"S \NAC"
BN"8"110;
%"TAP"
"1","(-6025,2600)","0","mstr_standard","I44";
;
CDS_LIB"mstr_standard"
BODY_TYPE"PLUMBING"
HDL_TAP"TRUE";
"B \NAC \NWC"11;
"S \NAC"
BN"9"109;
%"TAP"
"1","(-6025,2650)","0","mstr_standard","I45";
;
CDS_LIB"mstr_standard"
BODY_TYPE"PLUMBING"
HDL_TAP"TRUE";
"B \NAC \NWC"11;
"S \NAC"
BN"10"108;
%"TAP"
"1","(-6025,2700)","0","mstr_standard","I46";
;
CDS_LIB"mstr_standard"
BODY_TYPE"PLUMBING"
HDL_TAP"TRUE";
"B \NAC \NWC"11;
"S \NAC"
BN"11"107;
%"TAP"
"1","(-6025,2750)","0","mstr_standard","I47";
;
CDS_LIB"mstr_standard"
BODY_TYPE"PLUMBING"
HDL_TAP"TRUE";
"B \NAC \NWC"11;
"S \NAC"
BN"12"106;
%"TAP"
"1","(-6025,2800)","0","mstr_standard","I48";
;
CDS_LIB"mstr_standard"
BODY_TYPE"PLUMBING"
HDL_TAP"TRUE";
"B \NAC \NWC"11;
"S \NAC"
BN"13"105;
%"TAP"
"1","(-6025,2850)","0","mstr_standard","I49";
;
CDS_LIB"mstr_standard"
BODY_TYPE"PLUMBING"
HDL_TAP"TRUE";
"B \NAC \NWC"11;
"S \NAC"
BN"14"104;
%"VCC_CORE"
"1","(-8550,3375)","0","mstr_symbols","I5";
;
HDL_POWER"P3V3_AUX"
ROOM"PVCCINFAON_CPU0_CTRL"
VOLTAGE"3.3"
CDS_LIB"mstr_symbols";
"A"21;
%"TAP"
"1","(-6025,2950)","0","mstr_standard","I50";
;
CDS_LIB"mstr_standard"
BODY_TYPE"PLUMBING"
HDL_TAP"TRUE";
"B \NAC \NWC"11;
"S \NAC"
BN"16"102;
%"TAP"
"1","(-6025,2900)","0","mstr_standard","I51";
;
CDS_LIB"mstr_standard"
BODY_TYPE"PLUMBING"
HDL_TAP"TRUE";
"B \NAC \NWC"11;
"S \NAC"
BN"15"103;
%"TAP"
"1","(-6025,3000)","0","mstr_standard","I52";
;
CDS_LIB"mstr_standard"
BODY_TYPE"PLUMBING"
HDL_TAP"TRUE";
"B \NAC \NWC"11;
"S \NAC"
BN"17"101;
%"TAP"
"1","(-6025,3100)","0","mstr_standard","I53";
;
CDS_LIB"mstr_standard"
BODY_TYPE"PLUMBING"
HDL_TAP"TRUE";
"B \NAC \NWC"11;
"S \NAC"
BN"19"99;
%"TAP"
"1","(-6025,3150)","0","mstr_standard","I54";
;
CDS_LIB"mstr_standard"
BODY_TYPE"PLUMBING"
HDL_TAP"TRUE";
"B \NAC \NWC"11;
"S \NAC"
BN"20"98;
%"TAP"
"1","(-6025,3250)","0","mstr_standard","I55";
;
CDS_LIB"mstr_standard"
BODY_TYPE"PLUMBING"
HDL_TAP"TRUE";
"B \NAC \NWC"11;
"S \NAC"
BN"22"96;
%"TAP"
"1","(-6025,3200)","0","mstr_standard","I56";
;
CDS_LIB"mstr_standard"
BODY_TYPE"PLUMBING"
HDL_TAP"TRUE";
"B \NAC \NWC"11;
"S \NAC"
BN"21"97;
%"TAP"
"1","(-6025,3050)","0","mstr_standard","I57";
;
CDS_LIB"mstr_standard"
BODY_TYPE"PLUMBING"
HDL_TAP"TRUE";
"B \NAC \NWC"11;
"S \NAC"
BN"18"100;
%"TAP"
"1","(-6025,3350)","0","mstr_standard","I58";
;
CDS_LIB"mstr_standard"
BODY_TYPE"PLUMBING"
HDL_TAP"TRUE";
"B \NAC \NWC"11;
"S \NAC"
BN"24"94;
%"TAP"
"1","(-6025,3400)","0","mstr_standard","I59";
;
CDS_LIB"mstr_standard"
BODY_TYPE"PLUMBING"
HDL_TAP"TRUE";
"B \NAC \NWC"11;
"S \NAC"
BN"25"93;
%"TAP"
"1","(-6025,3500)","0","mstr_standard","I60";
;
CDS_LIB"mstr_standard"
BODY_TYPE"PLUMBING"
HDL_TAP"TRUE";
"B \NAC \NWC"11;
"S \NAC"
BN"27"91;
%"TAP"
"1","(-6025,3450)","0","mstr_standard","I61";
;
CDS_LIB"mstr_standard"
BODY_TYPE"PLUMBING"
HDL_TAP"TRUE";
"B \NAC \NWC"11;
"S \NAC"
BN"26"92;
%"TAP"
"1","(-6025,3300)","0","mstr_standard","I62";
;
CDS_LIB"mstr_standard"
BODY_TYPE"PLUMBING"
HDL_TAP"TRUE";
"B \NAC \NWC"11;
"S \NAC"
BN"23"95;
%"TAP"
"1","(-6025,3600)","0","mstr_standard","I63";
;
CDS_LIB"mstr_standard"
BODY_TYPE"PLUMBING"
HDL_TAP"TRUE";
"B \NAC \NWC"11;
"S \NAC"
BN"29"89;
%"TAP"
"1","(-6025,3700)","0","mstr_standard","I64";
;
CDS_LIB"mstr_standard"
BODY_TYPE"PLUMBING"
HDL_TAP"TRUE";
"B \NAC \NWC"11;
"S \NAC"
BN"31"87;
%"TAP"
"1","(-6025,3650)","0","mstr_standard","I65";
;
CDS_LIB"mstr_standard"
BODY_TYPE"PLUMBING"
HDL_TAP"TRUE";
"B \NAC \NWC"11;
"S \NAC"
BN"30"88;
%"TAP"
"1","(-6025,3550)","0","mstr_standard","I66";
;
CDS_LIB"mstr_standard"
BODY_TYPE"PLUMBING"
HDL_TAP"TRUE";
"B \NAC \NWC"11;
"S \NAC"
BN"28"90;
%"TAP"
"1","(-7725,3800)","2","mstr_standard","I76";
;
CDS_LIB"mstr_standard"
BODY_TYPE"PLUMBING"
HDL_TAP"TRUE";
"B \NAC \NWC"12;
"S \NAC"
BN"4"28;
%"TAP"
"1","(-7725,3850)","2","mstr_standard","I77";
;
CDS_LIB"mstr_standard"
BODY_TYPE"PLUMBING"
HDL_TAP"TRUE";
"B \NAC \NWC"12;
"S \NAC"
BN"5"43;
%"TAP"
"1","(-7725,3950)","2","mstr_standard","I78";
;
CDS_LIB"mstr_standard"
BODY_TYPE"PLUMBING"
HDL_TAP"TRUE";
"B \NAC \NWC"12;
"S \NAC"
BN"7"27;
%"TAP"
"1","(-7725,3900)","2","mstr_standard","I79";
;
CDS_LIB"mstr_standard"
BODY_TYPE"PLUMBING"
HDL_TAP"TRUE";
"B \NAC \NWC"12;
"S \NAC"
BN"6"42;
%"TAP"
"1","(-7725,4650)","2","mstr_standard","I80";
;
CDS_LIB"mstr_standard"
BODY_TYPE"PLUMBING"
HDL_TAP"TRUE";
"B \NAC \NWC"13;
"S \NAC"
BN"0"32;
%"TAP"
"1","(-7725,4700)","2","mstr_standard","I81";
;
CDS_LIB"mstr_standard"
BODY_TYPE"PLUMBING"
HDL_TAP"TRUE";
"B \NAC \NWC"13;
"S \NAC"
BN"1"34;
%"TAP"
"1","(-7725,4750)","2","mstr_standard","I82";
;
CDS_LIB"mstr_standard"
BODY_TYPE"PLUMBING"
HDL_TAP"TRUE";
"B \NAC \NWC"13;
"S \NAC"
BN"2"36;
%"TAP"
"1","(-7725,4850)","2","mstr_standard","I83";
;
CDS_LIB"mstr_standard"
BODY_TYPE"PLUMBING"
HDL_TAP"TRUE";
"B \NAC \NWC"13;
"S \NAC"
BN"4"39;
%"TAP"
"1","(-7725,4800)","2","mstr_standard","I84";
;
CDS_LIB"mstr_standard"
BODY_TYPE"PLUMBING"
HDL_TAP"TRUE";
"B \NAC \NWC"13;
"S \NAC"
BN"3"38;
%"TAP"
"1","(-7725,4900)","2","mstr_standard","I85";
;
CDS_LIB"mstr_standard"
BODY_TYPE"PLUMBING"
HDL_TAP"TRUE";
"B \NAC \NWC"13;
"S \NAC"
BN"5"40;
%"TAP"
"1","(-7725,4950)","2","mstr_standard","I86";
;
CDS_LIB"mstr_standard"
BODY_TYPE"PLUMBING"
HDL_TAP"TRUE";
"B \NAC \NWC"13;
"S \NAC"
BN"6"41;
%"TAP"
"1","(-7725,5050)","2","mstr_standard","I87";
;
CDS_LIB"mstr_standard"
BODY_TYPE"PLUMBING"
HDL_TAP"TRUE";
"B \NAC \NWC"6;
"S \NAC"
BN"0"31;
%"TAP"
"1","(-7725,5100)","2","mstr_standard","I88";
;
CDS_LIB"mstr_standard"
BODY_TYPE"PLUMBING"
HDL_TAP"TRUE";
"B \NAC \NWC"6;
"S \NAC"
BN"1"33;
%"TAP"
"1","(-7725,5150)","2","mstr_standard","I89";
;
CDS_LIB"mstr_standard"
BODY_TYPE"PLUMBING"
HDL_TAP"TRUE";
"B \NAC \NWC"6;
"S \NAC"
BN"2"35;
%"TAP"
"1","(-7725,5200)","2","mstr_standard","I90";
;
CDS_LIB"mstr_standard"
BODY_TYPE"PLUMBING"
HDL_TAP"TRUE";
"B \NAC \NWC"6;
"S \NAC"
BN"3"37;
%"TAP"
"1","(-7725,5250)","2","mstr_standard","I91";
;
CDS_LIB"mstr_standard"
BODY_TYPE"PLUMBING"
HDL_TAP"TRUE";
"B \NAC \NWC"6;
"S \NAC"
BN"4"162;
%"TAP"
"1","(-7725,5300)","2","mstr_standard","I92";
;
CDS_LIB"mstr_standard"
BODY_TYPE"PLUMBING"
HDL_TAP"TRUE";
"B \NAC \NWC"6;
"S \NAC"
BN"5"163;
%"TAP"
"1","(-7725,5350)","2","mstr_standard","I93";
;
CDS_LIB"mstr_standard"
BODY_TYPE"PLUMBING"
HDL_TAP"TRUE";
"B \NAC \NWC"6;
"S \NAC"
BN"6"164;
%"TAP"
"1","(-6025,3800)","0","mstr_standard","I94";
;
CDS_LIB"mstr_standard"
BODY_TYPE"PLUMBING"
HDL_TAP"TRUE";
"B \NAC \NWC"5;
"S \NAC"
BN"0"86;
%"TAP"
"1","(-6025,3850)","0","mstr_standard","I95";
;
CDS_LIB"mstr_standard"
BODY_TYPE"PLUMBING"
HDL_TAP"TRUE";
"B \NAC \NWC"5;
"S \NAC"
BN"1"85;
%"TAP"
"1","(-6025,3900)","0","mstr_standard","I96";
;
CDS_LIB"mstr_standard"
BODY_TYPE"PLUMBING"
HDL_TAP"TRUE";
"B \NAC \NWC"5;
"S \NAC"
BN"2"84;
%"TAP"
"1","(-6025,3950)","0","mstr_standard","I97";
;
CDS_LIB"mstr_standard"
BODY_TYPE"PLUMBING"
HDL_TAP"TRUE";
"B \NAC \NWC"5;
"S \NAC"
BN"3"83;
%"TAP"
"1","(-6025,4000)","0","mstr_standard","I98";
;
CDS_LIB"mstr_standard"
BODY_TYPE"PLUMBING"
HDL_TAP"TRUE";
"B \NAC \NWC"5;
"S \NAC"
BN"4"82;
%"TAP"
"1","(-6025,4050)","0","mstr_standard","I99";
;
CDS_LIB"mstr_standard"
BODY_TYPE"PLUMBING"
HDL_TAP"TRUE";
"B \NAC \NWC"5;
"S \NAC"
BN"5"81;
END.
